(kicad_pcb
	(version 20260206)
	(generator "pcbnew")
	(generator_version "10.0")
	(general
		(thickness 1.6)
		(legacy_teardrops no)
	)
	(paper "A4")
	(title_block
		(title "03242023_DA0F0TMBIJ0_F0T_Motherboard_J_brd_V01_OCP.brd")
		(comment 1 "Grand Teton / footprints 5936-5941 of 6105")
	)
	(layers
		(0 "F.Cu" signal "TOP")
		(4 "In1.Cu" signal "GND")
		(6 "In2.Cu" signal "IN1")
		(8 "In3.Cu" signal "GND1")
		(10 "In4.Cu" signal "IN2")
		(12 "In5.Cu" signal "GND2")
		(14 "In6.Cu" signal "IN3")
		(16 "In7.Cu" signal "GND3")
		(18 "In8.Cu" signal "VCC")
		(20 "In9.Cu" signal "VCC1")
		(22 "In10.Cu" signal "GND4")
		(24 "In11.Cu" signal "IN4")
		(26 "In12.Cu" signal "GND5")
		(28 "In13.Cu" signal "IN5")
		(30 "In14.Cu" signal "GND6")
		(32 "In15.Cu" signal "IN6")
		(34 "In16.Cu" signal "GND7")
		(2 "B.Cu" signal "BOTTOM")
		(9 "F.Adhes" user "F.Adhesive")
		(11 "B.Adhes" user "B.Adhesive")
		(13 "F.Paste" user "Package Geometry/Pastemask Top")
		(15 "B.Paste" user "Package Geometry/Pastemask Bottom")
		(5 "F.SilkS" user "Ref Des/Silkscreen Top")
		(7 "B.SilkS" user "Ref Des/Silkscreen Bottom")
		(1 "F.Mask" user "Board Geometry/Soldermask Top")
		(3 "B.Mask" user "Board Geometry/Soldermask Bottom")
		(17 "Dwgs.User" user "User.Drawings")
		(19 "Cmts.User" user "User.Comments")
		(21 "Eco1.User" user "User.Eco1")
		(23 "Eco2.User" user "User.Eco2")
		(25 "Edge.Cuts" user "Board Geometry/Outline")
		(27 "Margin" user)
		(31 "F.CrtYd" user "Package Geometry/Place Bound Top")
		(29 "B.CrtYd" user "Package Geometry/Place Bound Bottom")
		(35 "F.Fab" user "Ref Des/Assembly Top")
		(33 "B.Fab" user "Ref Des/Assembly Bottom")
	)
	(footprint ""
		(layer "B.Cu")
		(at 433.077366 -311.86374 90)
		(property "Reference" "R2500"
			(at 0 0 90)
			(layer "B.SilkS")
			(hide yes)
			(effects
				(font
					(size 1.27 1.27)
				)
				(justify mirror)
			)
		)
		(property "Value" ""
			(at 0 0 90)
			(layer "B.Fab")
			(effects
				(font
					(size 1.27 1.27)
				)
				(justify mirror)
			)
		)
		(duplicate_pad_numbers_are_jumpers no)
		(fp_line
			(start 0.7874 -0.4064)
			(end -0.7874 -0.4064)
			(stroke
				(width 0.1524)
				(type default)
			)
			(layer "B.SilkS")
		)
		(fp_line
			(start -0.7874 -0.4064)
			(end -0.7874 0.4064)
			(stroke
				(width 0.1524)
				(type default)
			)
			(layer "B.SilkS")
		)
		(fp_line
			(start 0.7874 0.4064)
			(end 0.7874 -0.4064)
			(stroke
				(width 0.1524)
				(type default)
			)
			(layer "B.SilkS")
		)
		(fp_line
			(start -0.7874 0.4064)
			(end 0.7874 0.4064)
			(stroke
				(width 0.1524)
				(type default)
			)
			(layer "B.SilkS")
		)
		(fp_line
			(start 0.67945 -0.305054)
			(end 0.12065 -0.305054)
			(stroke
				(width 0.1)
				(type default)
			)
			(layer "B.Fab")
		)
		(fp_line
			(start 0.12065 -0.305054)
			(end 0.12065 -0.2794)
			(stroke
				(width 0.1)
				(type default)
			)
			(layer "B.Fab")
		)
		(fp_line
			(start -0.12065 -0.3048)
			(end -0.67945 -0.3048)
			(stroke
				(width 0.1)
				(type default)
			)
			(layer "B.Fab")
		)
		(fp_line
			(start -0.67945 -0.3048)
			(end -0.67945 0.3048)
			(stroke
				(width 0.1)
				(type default)
			)
			(layer "B.Fab")
		)
		(fp_line
			(start 0.12065 -0.2794)
			(end -0.12065 -0.2794)
			(stroke
				(width 0.1)
				(type default)
			)
			(layer "B.Fab")
		)
		(fp_line
			(start -0.12065 -0.2794)
			(end -0.12065 -0.3048)
			(stroke
				(width 0.1)
				(type default)
			)
			(layer "B.Fab")
		)
		(fp_line
			(start 0.12065 0.2794)
			(end 0.12065 0.3048)
			(stroke
				(width 0.1)
				(type default)
			)
			(layer "B.Fab")
		)
		(fp_line
			(start -0.120396 0.2794)
			(end 0.12065 0.2794)
			(stroke
				(width 0.1)
				(type default)
			)
			(layer "B.Fab")
		)
		(fp_line
			(start 0.67945 0.3048)
			(end 0.67945 -0.305054)
			(stroke
				(width 0.1)
				(type default)
			)
			(layer "B.Fab")
		)
		(fp_line
			(start 0.12065 0.3048)
			(end 0.67945 0.3048)
			(stroke
				(width 0.1)
				(type default)
			)
			(layer "B.Fab")
		)
		(fp_line
			(start -0.120396 0.3048)
			(end -0.120396 0.2794)
			(stroke
				(width 0.1)
				(type default)
			)
			(layer "B.Fab")
		)
		(fp_line
			(start -0.67945 0.3048)
			(end -0.120396 0.3048)
			(stroke
				(width 0.1)
				(type default)
			)
			(layer "B.Fab")
		)
		(pad "1" smd circle
			(at 0.40005 0 270)
			(size 0 0)
			(layers "B.Cu" "B.Mask" "B.Paste")
			(net "PWRGD_FAIL_CPU0_EF_R1")
		)
		(pad "2" smd circle
			(at -0.40005 0 270)
			(size 0 0)
			(layers "B.Cu" "B.Mask" "B.Paste")
			(net "PWRGD_FAIL_CPU0_EF_R")
		)
	)
	(footprint ""
		(layer "B.Cu")
		(at 331.312774 -63.123064 45)
		(property "Reference" "C1258"
			(at 0 0 45)
			(layer "B.SilkS")
			(hide yes)
			(effects
				(font
					(size 1.27 1.27)
				)
				(justify mirror)
			)
		)
		(property "Value" ""
			(at 0 0 45)
			(layer "B.Fab")
			(effects
				(font
					(size 1.27 1.27)
				)
				(justify mirror)
			)
		)
		(duplicate_pad_numbers_are_jumpers no)
		(fp_line
			(start -1.523949 -0.762065)
			(end -1.523949 0.762065)
			(stroke
				(width 0.1524)
				(type default)
			)
			(layer "B.SilkS")
		)
		(fp_line
			(start -1.523949 0.762065)
			(end 1.523949 0.762065)
			(stroke
				(width 0.1524)
				(type default)
			)
			(layer "B.SilkS")
		)
		(fp_line
			(start 1.523949 -0.762065)
			(end -1.523949 -0.762065)
			(stroke
				(width 0.1524)
				(type default)
			)
			(layer "B.SilkS")
		)
		(fp_line
			(start 1.523949 0.762065)
			(end 1.523949 -0.762065)
			(stroke
				(width 0.1524)
				(type default)
			)
			(layer "B.SilkS")
		)
		(fp_line
			(start -1.104931 -0.724886)
			(end 1.104931 -0.724886)
			(stroke
				(width 0.1)
				(type default)
			)
			(layer "B.Fab")
		)
		(fp_line
			(start -1.104931 0.724886)
			(end -1.104931 -0.724886)
			(stroke
				(width 0.1)
				(type default)
			)
			(layer "B.Fab")
		)
		(fp_line
			(start 1.104931 -0.724886)
			(end 1.104931 0.724886)
			(stroke
				(width 0.1)
				(type default)
			)
			(layer "B.Fab")
		)
		(fp_line
			(start 1.104931 0.724886)
			(end -1.104931 0.724886)
			(stroke
				(width 0.1)
				(type default)
			)
			(layer "B.Fab")
		)
		(pad "1" smd rect
			(at 0.889 0 45)
			(size 1.016 1.27)
			(layers "B.Cu" "B.Mask" "B.Paste")
			(net "P1V05_PCH_PLL_AUX")
		)
		(pad "2" smd rect
			(at -0.889 0 45)
			(size 1.016 1.27)
			(layers "B.Cu" "B.Mask" "B.Paste")
			(net "GND")
		)
	)
	(footprint ""
		(layer "B.Cu")
		(at 121.830084 -359.596436 -90)
		(property "Reference" "PJ67"
			(at -4.219702 -2.927096 0)
			(unlocked yes)
			(layer "B.SilkS")
			(effects
				(font
					(size 0.7874 0.5842)
					(thickness 0.1524)
				)
				(justify left mirror)
			)
		)
		(property "Value" ""
			(at 0 0 90)
			(layer "B.Fab")
			(effects
				(font
					(size 1.27 1.27)
				)
				(justify mirror)
			)
		)
		(duplicate_pad_numbers_are_jumpers no)
		(pad "1" smd circle
			(at 0.7493 0)
			(size 0 0)
			(layers "B.Cu" "B.Mask" "B.Paste")
			(net "SH_PVPP_HBM_CPU1_N")
		)
		(pad "2" smd rect
			(at -0.7493 0 180)
			(size 0.7112 0.8128)
			(layers "B.Cu" "B.Mask" "B.Paste")
			(net "GND")
		)
		(zone
			(layer "B.Cu")
			(hatch none 0.5)
			(connect_pads
				(clearance 0)
			)
			(min_thickness 0.25)
			(keepout
				(tracks allowed)
				(vias not_allowed)
				(pads allowed)
				(copperpour not_allowed)
				(footprints allowed)
			)
			(placement
				(enabled no)
				(sheetname "")
			)
			(fill
				(thermal_gap 0.5)
				(thermal_bridge_width 0.5)
				(island_removal_mode 0)
			)
			(polygon
				(pts
					(xy 121.418858 -358.415336) (xy 122.236484 -358.415336) (xy 122.236484 -360.802936) (xy 121.418858 -360.802936)
				)
			)
		)
	)
	(footprint ""
		(layer "B.Cu")
		(at 335.741264 -184.827926 90)
		(property "Reference" "R21"
			(at 0 0 90)
			(layer "B.SilkS")
			(hide yes)
			(effects
				(font
					(size 1.27 1.27)
				)
				(justify mirror)
			)
		)
		(property "Value" ""
			(at 0 0 90)
			(layer "B.Fab")
			(effects
				(font
					(size 1.27 1.27)
				)
				(justify mirror)
			)
		)
		(duplicate_pad_numbers_are_jumpers no)
		(fp_line
			(start 0.7874 -0.4064)
			(end -0.7874 -0.4064)
			(stroke
				(width 0.1524)
				(type default)
			)
			(layer "B.SilkS")
		)
		(fp_line
			(start -0.7874 -0.4064)
			(end -0.7874 0.4064)
			(stroke
				(width 0.1524)
				(type default)
			)
			(layer "B.SilkS")
		)
		(fp_line
			(start 0.7874 0.4064)
			(end 0.7874 -0.4064)
			(stroke
				(width 0.1524)
				(type default)
			)
			(layer "B.SilkS")
		)
		(fp_line
			(start -0.7874 0.4064)
			(end 0.7874 0.4064)
			(stroke
				(width 0.1524)
				(type default)
			)
			(layer "B.SilkS")
		)
		(fp_line
			(start 0.67945 -0.305054)
			(end 0.12065 -0.305054)
			(stroke
				(width 0.1)
				(type default)
			)
			(layer "B.Fab")
		)
		(fp_line
			(start 0.12065 -0.305054)
			(end 0.12065 -0.2794)
			(stroke
				(width 0.1)
				(type default)
			)
			(layer "B.Fab")
		)
		(fp_line
			(start -0.12065 -0.3048)
			(end -0.67945 -0.3048)
			(stroke
				(width 0.1)
				(type default)
			)
			(layer "B.Fab")
		)
		(fp_line
			(start -0.67945 -0.3048)
			(end -0.67945 0.3048)
			(stroke
				(width 0.1)
				(type default)
			)
			(layer "B.Fab")
		)
		(fp_line
			(start 0.12065 -0.2794)
			(end -0.12065 -0.2794)
			(stroke
				(width 0.1)
				(type default)
			)
			(layer "B.Fab")
		)
		(fp_line
			(start -0.12065 -0.2794)
			(end -0.12065 -0.3048)
			(stroke
				(width 0.1)
				(type default)
			)
			(layer "B.Fab")
		)
		(fp_line
			(start 0.12065 0.2794)
			(end 0.12065 0.3048)
			(stroke
				(width 0.1)
				(type default)
			)
			(layer "B.Fab")
		)
		(fp_line
			(start -0.120396 0.2794)
			(end 0.12065 0.2794)
			(stroke
				(width 0.1)
				(type default)
			)
			(layer "B.Fab")
		)
		(fp_line
			(start 0.67945 0.3048)
			(end 0.67945 -0.305054)
			(stroke
				(width 0.1)
				(type default)
			)
			(layer "B.Fab")
		)
		(fp_line
			(start 0.12065 0.3048)
			(end 0.67945 0.3048)
			(stroke
				(width 0.1)
				(type default)
			)
			(layer "B.Fab")
		)
		(fp_line
			(start -0.120396 0.3048)
			(end -0.120396 0.2794)
			(stroke
				(width 0.1)
				(type default)
			)
			(layer "B.Fab")
		)
		(fp_line
			(start -0.67945 0.3048)
			(end -0.120396 0.3048)
			(stroke
				(width 0.1)
				(type default)
			)
			(layer "B.Fab")
		)
		(pad "1" smd circle
			(at 0.40005 0 270)
			(size 0 0)
			(layers "B.Cu" "B.Mask" "B.Paste")
			(net "DBP_CPU_MBP1_GTL_N")
		)
		(pad "2" smd circle
			(at -0.40005 0 270)
			(size 0 0)
			(layers "B.Cu" "B.Mask" "B.Paste")
			(net "FM_PCH_TRIGGER1_N")
		)
	)
	(footprint ""
		(layer "B.Cu")
		(at 60.082684 -174.152306)
		(property "Reference" "PC1930"
			(at 0 0 0)
			(layer "B.SilkS")
			(hide yes)
			(effects
				(font
					(size 1.27 1.27)
				)
				(justify mirror)
			)
		)
		(property "Value" ""
			(at 0 0 0)
			(layer "B.Fab")
			(effects
				(font
					(size 1.27 1.27)
				)
				(justify mirror)
			)
		)
		(duplicate_pad_numbers_are_jumpers no)
		(fp_line
			(start -4.533392 -2.249932)
			(end -4.533392 2.249932)
			(stroke
				(width 0.1524)
				(type default)
			)
			(layer "B.SilkS")
		)
		(fp_line
			(start -4.533392 2.249932)
			(end 4.533392 2.249932)
			(stroke
				(width 0.1524)
				(type default)
			)
			(layer "B.SilkS")
		)
		(fp_line
			(start 4.533392 -2.249932)
			(end -4.533392 -2.249932)
			(stroke
				(width 0.1524)
				(type default)
			)
			(layer "B.SilkS")
		)
		(fp_line
			(start 4.533392 2.249932)
			(end 4.533392 -2.249932)
			(stroke
				(width 0.1524)
				(type default)
			)
			(layer "B.SilkS")
		)
		(fp_rect
			(start 4.533392 2.326132)
			(end 5.39242 -2.326132)
			(stroke
				(width 0)
				(type default)
			)
			(fill yes)
			(layer "B.SilkS")
		)
		(fp_line
			(start -3.750056 -2.249932)
			(end -3.750056 2.249932)
			(stroke
				(width 0.1)
				(type default)
			)
			(layer "B.Fab")
		)
		(fp_line
			(start -3.750056 2.249932)
			(end 3.750056 2.249932)
			(stroke
				(width 0.1)
				(type default)
			)
			(layer "B.Fab")
		)
		(fp_line
			(start 3.750056 -2.249932)
			(end -3.750056 -2.249932)
			(stroke
				(width 0.1)
				(type default)
			)
			(layer "B.Fab")
		)
		(fp_line
			(start 3.750056 2.249932)
			(end 3.750056 -2.249932)
			(stroke
				(width 0.1)
				(type default)
			)
			(layer "B.Fab")
		)
		(fp_text user "-"
			(at -4.8514 -0.14605 0)
			(unlocked yes)
			(layer "B.SilkS")
			(effects
				(font
					(size 1.905 1.4224)
					(thickness 0.1524)
				)
				(justify left mirror)
			)
		)
		(fp_text user "+"
			(at 6.322314 0.786384 270)
			(unlocked yes)
			(layer "B.SilkS")
			(effects
				(font
					(size 1.905 1.4224)
					(thickness 0.1524)
				)
				(justify left mirror)
			)
		)
		(fp_text user "-"
			(at -4.8514 -0.14605 0)
			(unlocked yes)
			(layer "B.Fab")
			(effects
				(font
					(size 1.905 1.4224)
					(thickness 0.1524)
				)
				(justify left mirror)
			)
		)
		(fp_text user "+"
			(at 6.322314 0.786384 270)
			(unlocked yes)
			(layer "B.Fab")
			(effects
				(font
					(size 1.905 1.4224)
					(thickness 0.1524)
				)
				(justify left mirror)
			)
		)
		(pad "1" smd rect
			(at 3.199892 0 180)
			(size 2.413 2.8194)
			(layers "B.Cu" "B.Mask" "B.Paste")
			(net "PVCCFA_EHV_CPU1")
		)
		(pad "2" smd rect
			(at -3.199892 0 180)
			(size 2.413 2.8194)
			(layers "B.Cu" "B.Mask" "B.Paste")
			(net "GND")
		)
	)
	(footprint ""
		(layer "B.Cu")
		(at 68.223638 -319.98539 -90)
		(property "Reference" "D46"
			(at -4.247388 -1.898142 0)
			(unlocked yes)
			(layer "B.SilkS")
			(effects
				(font
					(size 0.7874 0.5842)
					(thickness 0.1524)
				)
				(justify left mirror)
			)
		)
		(property "Value" ""
			(at 0 0 90)
			(layer "B.Fab")
			(effects
				(font
					(size 1.27 1.27)
				)
				(justify mirror)
			)
		)
		(duplicate_pad_numbers_are_jumpers no)
		(fp_line
			(start -2.050796 0.700024)
			(end 2.050796 0.700024)
			(stroke
				(width 0.1524)
				(type default)
			)
			(layer "B.SilkS")
		)
		(fp_line
			(start 2.050796 0.700024)
			(end 2.050796 -0.700024)
			(stroke
				(width 0.1524)
				(type default)
			)
			(layer "B.SilkS")
		)
		(fp_line
			(start -2.343404 0.6985)
			(end -2.216404 0.6985)
			(stroke
				(width 0.1524)
				(type default)
			)
			(layer "B.SilkS")
		)
		(fp_line
			(start -2.229104 0.6985)
			(end -2.051304 0.6985)
			(stroke
				(width 0.1524)
				(type default)
			)
			(layer "B.SilkS")
		)
		(fp_line
			(start -2.051304 0.6985)
			(end -2.051304 0.635)
			(stroke
				(width 0.1524)
				(type default)
			)
			(layer "B.SilkS")
		)
		(fp_line
			(start -2.152904 0.635)
			(end -2.152904 -0.6985)
			(stroke
				(width 0.1524)
				(type default)
			)
			(layer "B.SilkS")
		)
		(fp_line
			(start -2.051304 0.635)
			(end -2.152904 0.635)
			(stroke
				(width 0.1524)
				(type default)
			)
			(layer "B.SilkS")
		)
		(fp_line
			(start 0.30607 0.500126)
			(end -0.193802 0)
			(stroke
				(width 0.1524)
				(type default)
			)
			(layer "B.SilkS")
		)
		(fp_line
			(start -0.193802 0)
			(end 0.30607 -0.500126)
			(stroke
				(width 0.1524)
				(type default)
			)
			(layer "B.SilkS")
		)
		(fp_line
			(start -0.293878 -0.500126)
			(end -0.293878 0.500126)
			(stroke
				(width 0.1524)
				(type default)
			)
			(layer "B.SilkS")
		)
		(fp_line
			(start 0.30607 -0.500126)
			(end 0.30607 0.500126)
			(stroke
				(width 0.1524)
				(type default)
			)
			(layer "B.SilkS")
		)
		(fp_line
			(start -2.064004 -0.6731)
			(end -2.064004 -0.6985)
			(stroke
				(width 0.1524)
				(type default)
			)
			(layer "B.SilkS")
		)
		(fp_line
			(start -2.343404 -0.6985)
			(end -2.343404 0.6985)
			(stroke
				(width 0.1524)
				(type default)
			)
			(layer "B.SilkS")
		)
		(fp_line
			(start -2.229104 -0.6985)
			(end -2.229104 0.6985)
			(stroke
				(width 0.1524)
				(type default)
			)
			(layer "B.SilkS")
		)
		(fp_line
			(start -2.152904 -0.6985)
			(end -2.343404 -0.6985)
			(stroke
				(width 0.1524)
				(type default)
			)
			(layer "B.SilkS")
		)
		(fp_line
			(start -2.064004 -0.6985)
			(end -2.229104 -0.6985)
			(stroke
				(width 0.1524)
				(type default)
			)
			(layer "B.SilkS")
		)
		(fp_line
			(start -2.050796 -0.700024)
			(end -2.050796 0.700024)
			(stroke
				(width 0.1524)
				(type default)
			)
			(layer "B.SilkS")
		)
		(fp_line
			(start 2.050796 -0.700024)
			(end -2.050796 -0.700024)
			(stroke
				(width 0.1524)
				(type default)
			)
			(layer "B.SilkS")
		)
		(fp_line
			(start -0.899922 0.700024)
			(end 0.899922 0.700024)
			(stroke
				(width 0.1)
				(type default)
			)
			(layer "B.Fab")
		)
		(fp_line
			(start 0.899922 0.700024)
			(end 0.899922 -0.700024)
			(stroke
				(width 0.1)
				(type default)
			)
			(layer "B.Fab")
		)
		(fp_line
			(start -0.899922 -0.700024)
			(end -0.899922 0.700024)
			(stroke
				(width 0.1)
				(type default)
			)
			(layer "B.Fab")
		)
		(fp_line
			(start 0.899922 -0.700024)
			(end -0.899922 -0.700024)
			(stroke
				(width 0.1)
				(type default)
			)
			(layer "B.Fab")
		)
		(fp_text user "+"
			(at 3.123946 0.762 180)
			(unlocked yes)
			(layer "B.SilkS")
			(effects
				(font
					(size 1.905 1.4224)
					(thickness 0.1524)
				)
				(justify left mirror)
			)
		)
		(fp_text user "-"
			(at -3.880104 0.23495 90)
			(unlocked yes)
			(layer "B.SilkS")
			(effects
				(font
					(size 1.905 1.4224)
					(thickness 0.1524)
				)
				(justify left mirror)
			)
		)
		(fp_text user "+"
			(at 3.123946 0.762 180)
			(unlocked yes)
			(layer "B.Fab")
			(effects
				(font
					(size 1.905 1.4224)
					(thickness 0.1524)
				)
				(justify left mirror)
			)
		)
		(fp_text user "-"
			(at -3.880104 0.23495 90)
			(unlocked yes)
			(layer "B.Fab")
			(effects
				(font
					(size 1.905 1.4224)
					(thickness 0.1524)
				)
				(justify left mirror)
			)
		)
		(pad "1" smd rect
			(at 1.199896 0 180)
			(size 0.6604 1.3716)
			(layers "B.Cu" "B.Mask" "B.Paste")
			(net "PWRGD_FAIL_CPU1_AB_R1")
		)
		(pad "2" smd rect
			(at -1.199896 0)
			(size 0.6604 1.3716)
			(layers "B.Cu" "B.Mask" "B.Paste")
			(net "P3V3_AUX")
		)
	)
)
